(kicad_pcb
	(version 20260206)
	(generator "pcbnew")
	(generator_version "10.0")
	(general
		(thickness 1.6)
		(legacy_teardrops no)
	)
	(paper "A4")
	(title_block
		(title "Bryce Canyon_IOM_IOC_16318-2_OCP.brd")
		(comment 1 "Bryce Canyon / footprint 1106 of 1605 (U32), pads 1-14 of 14")
	)
	(layers
		(0 "F.Cu" signal "TOP")
		(4 "In1.Cu" signal "L2GND")
		(6 "In2.Cu" signal "L3")
		(8 "In3.Cu" signal "L4VCC")
		(10 "In4.Cu" signal "L5VCC")
		(12 "In5.Cu" signal "L6")
		(14 "In6.Cu" signal "L7GND")
		(2 "B.Cu" signal "BOTTOM")
		(9 "F.Adhes" user "F.Adhesive")
		(11 "B.Adhes" user "B.Adhesive")
		(13 "F.Paste" user "Package Geometry/Pastemask Top")
		(15 "B.Paste" user "Package Geometry/Pastemask Bottom")
		(5 "F.SilkS" user "Ref Des/Silkscreen Top")
		(7 "B.SilkS" user "Ref Des/Silkscreen Bottom")
		(1 "F.Mask" user "Board Geometry/Soldermask Top")
		(3 "B.Mask" user "Board Geometry/Soldermask Bottom")
		(17 "Dwgs.User" user "User.Drawings")
		(19 "Cmts.User" user "User.Comments")
		(21 "Eco1.User" user "User.Eco1")
		(23 "Eco2.User" user "User.Eco2")
		(25 "Edge.Cuts" user "Board Geometry/Outline")
		(27 "Margin" user)
		(31 "F.CrtYd" user "Package Geometry/Place Bound Top")
		(29 "B.CrtYd" user "Package Geometry/Place Bound Bottom")
		(35 "F.Fab" user "Ref Des/Assembly Top")
		(33 "B.Fab" user "Ref Des/Assembly Bottom")
	)
	(footprint ""
		(layer "B.Cu")
		(at 85.6996 -169.6974 90)
		(property "Reference" "U32"
			(at 0 0 90)
			(layer "B.SilkS")
			(hide yes)
			(effects
				(font
					(size 1.27 1.27)
				)
				(justify mirror)
			)
		)
		(property "Value" "SN74LVC126APWR-1-GP"
			(at 0 -10.6172 90)
			(unlocked yes)
			(layer "B.Fab")
			(hide yes)
			(effects
				(font
					(size 1.016 1.016)
					(thickness 0.1524)
				)
				(justify mirror)
			)
		)
		(property "Device Type" "SSOIC14-1H48"
			(at 0 -12.1412 90)
			(unlocked yes)
			(layer "B.Fab")
			(hide yes)
			(effects
				(font
					(size 1.016 1.016)
					(thickness 0.1524)
				)
				(justify mirror)
			)
		)
		(duplicate_pad_numbers_are_jumpers no)
		(pad "1" smd rect
			(at 1.95072 2.8194 270)
			(size 0.3556 1.524)
			(layers "B.Cu" "B.Mask" "B.Paste")
			(net "PCIE_RST_R_N")
		)
		(pad "2" smd rect
			(at 1.30048 2.8194 270)
			(size 0.3556 1.524)
			(layers "B.Cu" "B.Mask" "B.Paste")
			(net "UART_COMP_R_TX")
		)
		(pad "3" smd rect
			(at 0.65024 2.8194 270)
			(size 0.3556 1.524)
			(layers "B.Cu" "B.Mask" "B.Paste")
			(net "UART_COMP_OUT_TX")
		)
		(pad "4" smd rect
			(at 0 2.8194 270)
			(size 0.3556 1.524)
			(layers "B.Cu" "B.Mask" "B.Paste")
			(net "PCIE_RST_R_N")
		)
		(pad "5" smd rect
			(at -0.65024 2.8194 270)
			(size 0.3556 1.524)
			(layers "B.Cu" "B.Mask" "B.Paste")
			(net "UART_COMP_IN_RX_AND_R")
		)
		(pad "6" smd rect
			(at -1.30048 2.8194 270)
			(size 0.3556 1.524)
			(layers "B.Cu" "B.Mask" "B.Paste")
			(net "UART_COMP_R_RX")
		)
		(pad "7" smd rect
			(at -1.95072 2.8194 270)
			(size 0.3556 1.524)
			(layers "B.Cu" "B.Mask" "B.Paste")
			(net "GND")
		)
		(pad "8" smd rect
			(at -1.95072 -2.8194 270)
			(size 0.3556 1.524)
			(layers "B.Cu" "B.Mask" "B.Paste")
			(net "UART_EXP_BMC_TX")
		)
		(pad "9" smd rect
			(at -1.30048 -2.8194 270)
			(size 0.3556 1.524)
			(layers "B.Cu" "B.Mask" "B.Paste")
			(net "UART_SDB_TX_R")
		)
		(pad "10" smd rect
			(at -0.65024 -2.8194 270)
			(size 0.3556 1.524)
			(layers "B.Cu" "B.Mask" "B.Paste")
			(net "EXP_UART_EN_R")
		)
		(pad "11" smd rect
			(at 0 -2.8194 270)
			(size 0.3556 1.524)
			(layers "B.Cu" "B.Mask" "B.Paste")
			(net "UART_SDB_RX")
		)
		(pad "12" smd rect
			(at 0.65024 -2.8194 270)
			(size 0.3556 1.524)
			(layers "B.Cu" "B.Mask" "B.Paste")
			(net "UART_EXP_BMC_RX")
		)
		(pad "13" smd rect
			(at 1.30048 -2.8194 270)
			(size 0.3556 1.524)
			(layers "B.Cu" "B.Mask" "B.Paste")
			(net "EXP_UART_EN_R")
		)
		(pad "14" smd rect
			(at 1.95072 -2.8194 270)
			(size 0.3556 1.524)
			(layers "B.Cu" "B.Mask" "B.Paste")
			(net "P3V3_STBY")
		)
	)
)
